FILE_TYPE = CONNECTIVITY;
{Allegro Design Entry HDL 17.2-2016 S081 (4005846) 1/11/2022}
"PAGE_NUMBER" = 69;
0"NC";
1"GND\g";
2"PVDDCR_SOC_P0\g";
3"GND\g";
4"PVDDCR_SOC_P0\g";
5"GND\g";
6"PVDDCR_SOC_P0\g";
7"GND\g";
8"PVDDCR_SOC_P0\g";
9"GND\g";
10"PVDDCR_SOC_P0\g";
11"GND\g";
12"PVDDCR_SOC_P0\g";
13"GND\g";
14"PVDDCR_SOC_P0\g";
15"PVDDCR_SOC_P0\g";
16"GND\g";
17"PVDD11_S3_P0\g";
18"GND\g";
19"PVDD11_S3_P0\g";
20"GND\g";
21"PVDD11_S3_P0\g";
22"GND\g";
23"PVDD11_S3_P0\g";
24"GND\g";
25"PVDD11_S3_P0\g";
26"GND\g";
27"PVDDIO_P0\g";
28"GND\g";
29"PVDDIO_P0\g";
30"GND\g";
31"PVDDIO_P0\g";
32"GND\g";
%"Q_CAP"
"1","(-9075,875)","0","pure_quanta","I1";
;
LOCATION"C3925"
$SEC"1"
CDS_SEC"1"
MATERIAL"X6S"
TOLERANCE"20%"
VALUE"22UF"
PART_NUMBER"CH622KMEB02"
VOLTAGE"4V"
PACK_TYPE"C0402"
CDS_LIB"pure_quanta";
"B"
$PN"2"1;
"A"
$PN"1"4;
%"Q_CAP"
"1","(-8625,2300)","0","pure_quanta","I10";
;
LOCATION"C2539"
$SEC"1"
CDS_SEC"1"
MATERIAL"X6S"
TOLERANCE"20%"
VALUE"22UF"
PART_NUMBER"CH622KMEB02"
VOLTAGE"4V"
PACK_TYPE"C0402"
CDS_LIB"pure_quanta";
"B"
$PN"2"7;
"A"
$PN"1"6;
%"UNIVERSAL_GND"
"1","(-5100,4775)","0","pure_quanta_power","I100";
;
CDS_LIB"pure_quanta_power"
HDL_POWER"GND";
"A"11;
%"Q_CAP"
"1","(-5100,5150)","0","pure_quanta","I101";
;
LOCATION"C2591"
$SEC"1"
CDS_SEC"1"
MATERIAL"X6S"
TOLERANCE"20%"
VALUE"22UF"
PART_NUMBER"CH622KMEB02"
VOLTAGE"4V"
PACK_TYPE"C0402"
CDS_LIB"pure_quanta";
"B"
$PN"2"11;
"A"
$PN"1"14;
%"Q_CAP"
"1","(-4500,4325)","0","pure_quanta","I102";
;
LOCATION"C2599"
$SEC"1"
CDS_SEC"1"
MATERIAL"X6S"
TOLERANCE"20%"
VALUE"22UF"
PART_NUMBER"CH622KMEB02"
VOLTAGE"4V"
PACK_TYPE"C0402"
CDS_LIB"pure_quanta";
"B"
$PN"2"32;
"A"
$PN"1"31;
%"UNIVERSAL_POWER"
"1","(-4500,4600)","0","pure_quanta_power","I103";
;
HDL_POWER"PVDDIO_P0"
CDS_LIB"pure_quanta_power";
"A"31;
%"Q_CAP"
"1","(-4525,5100)","0","pure_quanta","I104";
;
LOCATION"C2598"
$SEC"1"
CDS_SEC"1"
MATERIAL"X6S"
TOLERANCE"20%"
VALUE"22UF"
PART_NUMBER"CH622KMEB02"
VOLTAGE"4V"
PACK_TYPE"C0402"
CDS_LIB"pure_quanta";
"B"
$PN"2"28;
"A"
$PN"1"27;
%"UNIVERSAL_GND"
"1","(-5100,5525)","0","pure_quanta_power","I105";
;
CDS_LIB"pure_quanta_power"
HDL_POWER"GND";
"A"16;
%"Q_CAP"
"1","(-5100,5900)","0","pure_quanta","I106";
;
LOCATION"C2590"
$SEC"1"
CDS_SEC"1"
MATERIAL"X6S"
TOLERANCE"20%"
VALUE"22UF"
PART_NUMBER"CH622KMEB02"
VOLTAGE"4V"
PACK_TYPE"C0402"
CDS_LIB"pure_quanta";
"B"
$PN"2"16;
"A"
$PN"1"15;
%"UNIVERSAL_POWER"
"1","(-4525,5375)","0","pure_quanta_power","I107";
;
HDL_POWER"PVDDIO_P0"
CDS_LIB"pure_quanta_power";
"A"27;
%"Q_CAP"
"1","(-4525,5900)","0","pure_quanta","I108";
;
LOCATION"C2597"
$SEC"1"
CDS_SEC"1"
MATERIAL"X6S"
TOLERANCE"20%"
VALUE"22UF"
PART_NUMBER"CH622KMEB02"
VOLTAGE"4V"
PACK_TYPE"C0402"
CDS_LIB"pure_quanta";
"B"
$PN"2"30;
"A"
$PN"1"29;
%"UNIVERSAL_POWER"
"1","(-4525,6175)","0","pure_quanta_power","I109";
;
HDL_POWER"PVDDIO_P0"
CDS_LIB"pure_quanta_power";
"A"29;
%"Q_CAP"
"1","(-8625,3000)","0","pure_quanta","I11";
;
LOCATION"C2538"
$SEC"1"
CDS_SEC"1"
MATERIAL"X6S"
TOLERANCE"20%"
VALUE"22UF"
PART_NUMBER"CH622KMEB02"
VOLTAGE"4V"
PACK_TYPE"C0402"
CDS_LIB"pure_quanta";
"B"
$PN"2"5;
"A"
$PN"1"10;
%"UNIVERSAL_GND"
"1","(-4050,475)","0","pure_quanta_power","I110";
;
CDS_LIB"pure_quanta_power"
HDL_POWER"GND";
"A"26;
%"Q_CAP"
"1","(-4050,800)","0","pure_quanta","I111";
;
LOCATION"C3933"
$SEC"1"
CDS_SEC"1"
MATERIAL"X6S"
TOLERANCE"20%"
VALUE"22UF"
PART_NUMBER"CH622KMEB02"
VOLTAGE"4V"
PACK_TYPE"C0402"
CDS_LIB"pure_quanta";
"B"
$PN"2"26;
"A"
$PN"1"25;
%"Q_CAP"
"1","(-4050,1400)","0","pure_quanta","I112";
;
LOCATION"C2610"
$SEC"1"
CDS_SEC"1"
MATERIAL"X6S"
TOLERANCE"20%"
VALUE"22UF"
PART_NUMBER"CH622KMEB02"
VOLTAGE"4V"
PACK_TYPE"C0402"
CDS_LIB"pure_quanta";
"B"
$PN"2"24;
"A"
$PN"1"23;
%"Q_CAP"
"1","(-4050,2000)","0","pure_quanta","I113";
;
LOCATION"C2609"
$SEC"1"
CDS_SEC"1"
MATERIAL"X6S"
TOLERANCE"20%"
VALUE"22UF"
PART_NUMBER"CH622KMEB02"
VOLTAGE"4V"
PACK_TYPE"C0402"
CDS_LIB"pure_quanta";
"B"
$PN"2"22;
"A"
$PN"1"21;
%"Q_CAP"
"1","(-3600,1400)","0","pure_quanta","I114";
;
LOCATION"C2617"
$SEC"1"
CDS_SEC"1"
MATERIAL"X6S"
TOLERANCE"20%"
VALUE"22UF"
PART_NUMBER"CH622KMEB02"
VOLTAGE"4V"
PACK_TYPE"C0402"
CDS_LIB"pure_quanta";
"B"
$PN"2"24;
"A"
$PN"1"23;
%"Q_CAP"
"1","(-3600,2000)","0","pure_quanta","I115";
;
LOCATION"C2616"
$SEC"1"
CDS_SEC"1"
MATERIAL"X6S"
TOLERANCE"20%"
VALUE"22UF"
PART_NUMBER"CH622KMEB02"
VOLTAGE"4V"
PACK_TYPE"C0402"
CDS_LIB"pure_quanta";
"B"
$PN"2"22;
"A"
$PN"1"21;
%"Q_CAP"
"1","(-3150,1400)","0","pure_quanta","I116";
;
LOCATION"C2624"
$SEC"1"
CDS_SEC"1"
MATERIAL"X6S"
TOLERANCE"20%"
VALUE"22UF"
PART_NUMBER"CH622KMEB02"
VOLTAGE"4V"
PACK_TYPE"C0402"
CDS_LIB"pure_quanta";
"B"
$PN"2"24;
"A"
$PN"1"23;
%"Q_CAP"
"1","(-3150,2000)","0","pure_quanta","I117";
;
LOCATION"C2623"
$SEC"1"
CDS_SEC"1"
MATERIAL"X6S"
TOLERANCE"20%"
VALUE"22UF"
PART_NUMBER"CH622KMEB02"
VOLTAGE"4V"
PACK_TYPE"C0402"
CDS_LIB"pure_quanta";
"B"
$PN"2"22;
"A"
$PN"1"21;
%"Q_CAP"
"1","(-2700,1400)","0","pure_quanta","I118";
;
LOCATION"C2630"
$SEC"1"
CDS_SEC"1"
MATERIAL"X6S"
TOLERANCE"20%"
VALUE"22UF"
PART_NUMBER"CH622KMEB02"
VOLTAGE"4V"
PACK_TYPE"C0402"
CDS_LIB"pure_quanta";
"B"
$PN"2"24;
"A"
$PN"1"23;
%"Q_CAP"
"1","(-2700,2000)","0","pure_quanta","I119";
;
LOCATION"C2629"
$SEC"1"
CDS_SEC"1"
MATERIAL"X6S"
TOLERANCE"20%"
VALUE"22UF"
PART_NUMBER"CH622KMEB02"
VOLTAGE"4V"
PACK_TYPE"C0402"
CDS_LIB"pure_quanta";
"B"
$PN"2"22;
"A"
$PN"1"21;
%"UNIVERSAL_POWER"
"1","(-9075,3275)","0","pure_quanta_power","I12";
;
HDL_POWER"PVDDCR_SOC_P0"
CDS_LIB"pure_quanta_power";
"A"10;
%"Q_CAP"
"1","(-2250,1400)","0","pure_quanta","I120";
;
LOCATION"C2636"
$SEC"1"
CDS_SEC"1"
MATERIAL"X6S"
TOLERANCE"20%"
VALUE"22UF"
PART_NUMBER"CH622KMEB02"
VOLTAGE"4V"
PACK_TYPE"C0402"
CDS_LIB"pure_quanta";
"B"
$PN"2"24;
"A"
$PN"1"23;
%"Q_CAP"
"1","(-2250,2000)","0","pure_quanta","I121";
;
LOCATION"C2635"
$SEC"1"
CDS_SEC"1"
MATERIAL"X6S"
TOLERANCE"20%"
VALUE"22UF"
PART_NUMBER"CH622KMEB02"
VOLTAGE"4V"
PACK_TYPE"C0402"
CDS_LIB"pure_quanta";
"B"
$PN"2"22;
"A"
$PN"1"21;
%"Q_CAP"
"1","(-4050,2625)","0","pure_quanta","I122";
;
LOCATION"C2608"
$SEC"1"
CDS_SEC"1"
MATERIAL"X6S"
TOLERANCE"20%"
VALUE"22UF"
PART_NUMBER"CH622KMEB02"
VOLTAGE"4V"
PACK_TYPE"C0402"
CDS_LIB"pure_quanta";
"B"
$PN"2"20;
"A"
$PN"1"19;
%"Q_CAP"
"1","(-3600,2625)","0","pure_quanta","I123";
;
LOCATION"C2615"
$SEC"1"
CDS_SEC"1"
MATERIAL"X6S"
TOLERANCE"20%"
VALUE"22UF"
PART_NUMBER"CH622KMEB02"
VOLTAGE"4V"
PACK_TYPE"C0402"
CDS_LIB"pure_quanta";
"B"
$PN"2"20;
"A"
$PN"1"19;
%"Q_CAP"
"1","(-4050,3275)","0","pure_quanta","I124";
;
LOCATION"C2607"
$SEC"1"
CDS_SEC"1"
MATERIAL"X6S"
TOLERANCE"20%"
VALUE"22UF"
PART_NUMBER"CH622KMEB02"
VOLTAGE"4V"
PACK_TYPE"C0402"
CDS_LIB"pure_quanta";
"B"
$PN"2"18;
"A"
$PN"1"17;
%"Q_CAP"
"1","(-3600,3275)","0","pure_quanta","I125";
;
LOCATION"C2614"
$SEC"1"
CDS_SEC"1"
MATERIAL"X6S"
TOLERANCE"20%"
VALUE"22UF"
PART_NUMBER"CH622KMEB02"
VOLTAGE"4V"
PACK_TYPE"C0402"
CDS_LIB"pure_quanta";
"B"
$PN"2"18;
"A"
$PN"1"17;
%"Q_CAP"
"1","(-3150,2625)","0","pure_quanta","I126";
;
LOCATION"C2622"
$SEC"1"
CDS_SEC"1"
MATERIAL"X6S"
TOLERANCE"20%"
VALUE"22UF"
PART_NUMBER"CH622KMEB02"
VOLTAGE"4V"
PACK_TYPE"C0402"
CDS_LIB"pure_quanta";
"B"
$PN"2"20;
"A"
$PN"1"19;
%"Q_CAP"
"1","(-3150,3275)","0","pure_quanta","I127";
;
LOCATION"C2621"
$SEC"1"
CDS_SEC"1"
MATERIAL"X6S"
TOLERANCE"20%"
VALUE"22UF"
PART_NUMBER"CH622KMEB02"
VOLTAGE"4V"
PACK_TYPE"C0402"
CDS_LIB"pure_quanta";
"B"
$PN"2"18;
"A"
$PN"1"17;
%"UNIVERSAL_GND"
"1","(-3150,3950)","0","pure_quanta_power","I128";
;
CDS_LIB"pure_quanta_power"
HDL_POWER"GND";
"A"32;
%"Q_CAP"
"1","(-2700,2625)","0","pure_quanta","I129";
;
LOCATION"C2628"
$SEC"1"
CDS_SEC"1"
MATERIAL"X6S"
TOLERANCE"20%"
VALUE"22UF"
PART_NUMBER"CH622KMEB02"
VOLTAGE"4V"
PACK_TYPE"C0402"
CDS_LIB"pure_quanta";
"B"
$PN"2"20;
"A"
$PN"1"19;
%"Q_CAP"
"1","(-9075,3725)","0","pure_quanta","I13";
;
LOCATION"C2530"
$SEC"1"
CDS_SEC"1"
MATERIAL"X6S"
TOLERANCE"20%"
VALUE"22UF"
PART_NUMBER"CH622KMEB02"
VOLTAGE"4V"
PACK_TYPE"C0402"
CDS_LIB"pure_quanta";
"B"
$PN"2"9;
"A"
$PN"1"8;
%"Q_CAP"
"1","(-2250,2625)","0","pure_quanta","I130";
;
LOCATION"C2634"
$SEC"1"
CDS_SEC"1"
MATERIAL"X6S"
TOLERANCE"20%"
VALUE"22UF"
PART_NUMBER"CH622KMEB02"
VOLTAGE"4V"
PACK_TYPE"C0402"
CDS_LIB"pure_quanta";
"B"
$PN"2"20;
"A"
$PN"1"19;
%"Q_CAP"
"1","(-2700,3275)","0","pure_quanta","I131";
;
LOCATION"C2627"
$SEC"1"
CDS_SEC"1"
MATERIAL"X6S"
TOLERANCE"20%"
VALUE"22UF"
PART_NUMBER"CH622KMEB02"
VOLTAGE"4V"
PACK_TYPE"C0402"
CDS_LIB"pure_quanta";
"B"
$PN"2"18;
"A"
$PN"1"17;
%"Q_CAP"
"1","(-2250,3275)","0","pure_quanta","I132";
;
LOCATION"C2633"
$SEC"1"
CDS_SEC"1"
MATERIAL"X6S"
TOLERANCE"20%"
VALUE"22UF"
PART_NUMBER"CH622KMEB02"
VOLTAGE"4V"
PACK_TYPE"C0402"
CDS_LIB"pure_quanta";
"B"
$PN"2"18;
"A"
$PN"1"17;
%"Q_CAP"
"1","(-1800,1400)","0","pure_quanta","I133";
;
LOCATION"C2642"
$SEC"1"
CDS_SEC"1"
MATERIAL"X6S"
TOLERANCE"20%"
VALUE"22UF"
PART_NUMBER"CH622KMEB02"
VOLTAGE"4V"
PACK_TYPE"C0402"
CDS_LIB"pure_quanta";
"B"
$PN"2"24;
"A"
$PN"1"23;
%"Q_CAP"
"1","(-1800,2000)","0","pure_quanta","I134";
;
LOCATION"C2641"
$SEC"1"
CDS_SEC"1"
MATERIAL"X6S"
TOLERANCE"20%"
VALUE"22UF"
PART_NUMBER"CH622KMEB02"
VOLTAGE"4V"
PACK_TYPE"C0402"
CDS_LIB"pure_quanta";
"B"
$PN"2"22;
"A"
$PN"1"21;
%"Q_CAP"
"1","(-1350,1400)","0","pure_quanta","I135";
;
LOCATION"C2648"
$SEC"1"
CDS_SEC"1"
MATERIAL"X6S"
TOLERANCE"20%"
VALUE"22UF"
PART_NUMBER"CH622KMEB02"
VOLTAGE"4V"
PACK_TYPE"C0402"
CDS_LIB"pure_quanta";
"B"
$PN"2"24;
"A"
$PN"1"23;
%"Q_CAP"
"1","(-1350,2000)","0","pure_quanta","I136";
;
LOCATION"C2647"
$SEC"1"
CDS_SEC"1"
MATERIAL"X6S"
TOLERANCE"20%"
VALUE"22UF"
PART_NUMBER"CH622KMEB02"
VOLTAGE"4V"
PACK_TYPE"C0402"
CDS_LIB"pure_quanta";
"B"
$PN"2"22;
"A"
$PN"1"21;
%"UNIVERSAL_GND"
"1","(-500,1025)","0","pure_quanta_power","I137";
;
CDS_LIB"pure_quanta_power"
HDL_POWER"GND";
"A"24;
%"Q_CAP"
"1","(-900,1400)","0","pure_quanta","I138";
;
LOCATION"C3934"
$SEC"1"
CDS_SEC"1"
MATERIAL"X6S"
TOLERANCE"20%"
VALUE"22UF"
PART_NUMBER"CH622KMEB02"
VOLTAGE"4V"
PACK_TYPE"C0402"
CDS_LIB"pure_quanta";
"B"
$PN"2"24;
"A"
$PN"1"23;
%"Q_CAP"
"1","(-900,2000)","0","pure_quanta","I139";
;
LOCATION"C2653"
$SEC"1"
CDS_SEC"1"
MATERIAL"X6S"
TOLERANCE"20%"
VALUE"22UF"
PART_NUMBER"CH622KMEB02"
VOLTAGE"4V"
PACK_TYPE"C0402"
CDS_LIB"pure_quanta";
"B"
$PN"2"22;
"A"
$PN"1"21;
%"UNIVERSAL_POWER"
"1","(-9075,4000)","0","pure_quanta_power","I14";
;
HDL_POWER"PVDDCR_SOC_P0"
CDS_LIB"pure_quanta_power";
"A"8;
%"Q_CAP"
"1","(-500,1400)","0","pure_quanta","I140";
;
LOCATION"C3935"
$SEC"1"
CDS_SEC"1"
MATERIAL"X6S"
TOLERANCE"20%"
VALUE"22UF"
PART_NUMBER"CH622KMEB02"
VOLTAGE"4V"
PACK_TYPE"C0402"
CDS_LIB"pure_quanta";
"B"
$PN"2"24;
"A"
$PN"1"23;
%"UNIVERSAL_GND"
"1","(-500,1625)","0","pure_quanta_power","I141";
;
CDS_LIB"pure_quanta_power"
HDL_POWER"GND";
"A"22;
%"Q_CAP"
"1","(-500,2000)","0","pure_quanta","I142";
;
LOCATION"C2658"
$SEC"1"
CDS_SEC"1"
MATERIAL"X6S"
TOLERANCE"20%"
VALUE"22UF"
PART_NUMBER"CH622KMEB02"
VOLTAGE"4V"
PACK_TYPE"C0402"
CDS_LIB"pure_quanta";
"B"
$PN"2"22;
"A"
$PN"1"21;
%"Q_CAP"
"1","(-1800,2625)","0","pure_quanta","I143";
;
LOCATION"C2640"
$SEC"1"
CDS_SEC"1"
MATERIAL"X6S"
TOLERANCE"20%"
VALUE"22UF"
PART_NUMBER"CH622KMEB02"
VOLTAGE"4V"
PACK_TYPE"C0402"
CDS_LIB"pure_quanta";
"B"
$PN"2"20;
"A"
$PN"1"19;
%"Q_CAP"
"1","(-1350,2625)","0","pure_quanta","I144";
;
LOCATION"C2646"
$SEC"1"
CDS_SEC"1"
MATERIAL"X6S"
TOLERANCE"20%"
VALUE"22UF"
PART_NUMBER"CH622KMEB02"
VOLTAGE"4V"
PACK_TYPE"C0402"
CDS_LIB"pure_quanta";
"B"
$PN"2"20;
"A"
$PN"1"19;
%"Q_CAP"
"1","(-1800,3275)","0","pure_quanta","I145";
;
LOCATION"C2639"
$SEC"1"
CDS_SEC"1"
MATERIAL"X6S"
TOLERANCE"20%"
VALUE"22UF"
PART_NUMBER"CH622KMEB02"
VOLTAGE"4V"
PACK_TYPE"C0402"
CDS_LIB"pure_quanta";
"B"
$PN"2"18;
"A"
$PN"1"17;
%"Q_CAP"
"1","(-1350,3275)","0","pure_quanta","I146";
;
LOCATION"C2645"
$SEC"1"
CDS_SEC"1"
MATERIAL"X6S"
TOLERANCE"20%"
VALUE"22UF"
PART_NUMBER"CH622KMEB02"
VOLTAGE"4V"
PACK_TYPE"C0402"
CDS_LIB"pure_quanta";
"B"
$PN"2"18;
"A"
$PN"1"17;
%"Q_CAP"
"1","(-900,2625)","0","pure_quanta","I147";
;
LOCATION"C2652"
$SEC"1"
CDS_SEC"1"
MATERIAL"X6S"
TOLERANCE"20%"
VALUE"22UF"
PART_NUMBER"CH622KMEB02"
VOLTAGE"4V"
PACK_TYPE"C0402"
CDS_LIB"pure_quanta";
"B"
$PN"2"20;
"A"
$PN"1"19;
%"UNIVERSAL_GND"
"1","(-500,2275)","0","pure_quanta_power","I148";
;
CDS_LIB"pure_quanta_power"
HDL_POWER"GND";
"A"20;
%"Q_CAP"
"1","(-500,2625)","0","pure_quanta","I149";
;
LOCATION"C2657"
$SEC"1"
CDS_SEC"1"
MATERIAL"X6S"
TOLERANCE"20%"
VALUE"22UF"
PART_NUMBER"CH622KMEB02"
VOLTAGE"4V"
PACK_TYPE"C0402"
CDS_LIB"pure_quanta";
"B"
$PN"2"20;
"A"
$PN"1"19;
%"Q_CAP"
"1","(-8625,3725)","0","pure_quanta","I15";
;
LOCATION"C2537"
$SEC"1"
CDS_SEC"1"
MATERIAL"X6S"
TOLERANCE"20%"
VALUE"22UF"
PART_NUMBER"CH622KMEB02"
VOLTAGE"4V"
PACK_TYPE"C0402"
CDS_LIB"pure_quanta";
"B"
$PN"2"9;
"A"
$PN"1"8;
%"UNIVERSAL_GND"
"1","(-500,2900)","0","pure_quanta_power","I150";
;
CDS_LIB"pure_quanta_power"
HDL_POWER"GND";
"A"18;
%"Q_CAP"
"1","(-900,3275)","0","pure_quanta","I151";
;
LOCATION"C2651"
$SEC"1"
CDS_SEC"1"
MATERIAL"X6S"
TOLERANCE"20%"
VALUE"22UF"
PART_NUMBER"CH622KMEB02"
VOLTAGE"4V"
PACK_TYPE"C0402"
CDS_LIB"pure_quanta";
"B"
$PN"2"18;
"A"
$PN"1"17;
%"Q_CAP"
"1","(-500,3275)","0","pure_quanta","I152";
;
LOCATION"C2656"
$SEC"1"
CDS_SEC"1"
MATERIAL"X6S"
TOLERANCE"20%"
VALUE"22UF"
PART_NUMBER"CH622KMEB02"
VOLTAGE"4V"
PACK_TYPE"C0402"
CDS_LIB"pure_quanta";
"B"
$PN"2"18;
"A"
$PN"1"17;
%"Q_CAP"
"1","(-4050,4325)","0","pure_quanta","I153";
;
LOCATION"C2606"
$SEC"1"
CDS_SEC"1"
MATERIAL"X6S"
TOLERANCE"20%"
VALUE"22UF"
PART_NUMBER"CH622KMEB02"
VOLTAGE"4V"
PACK_TYPE"C0402"
CDS_LIB"pure_quanta";
"B"
$PN"2"32;
"A"
$PN"1"31;
%"Q_CAP"
"1","(-4075,5100)","0","pure_quanta","I154";
;
LOCATION"C2605"
$SEC"1"
CDS_SEC"1"
MATERIAL"X6S"
TOLERANCE"20%"
VALUE"22UF"
PART_NUMBER"CH622KMEB02"
VOLTAGE"4V"
PACK_TYPE"C0402"
CDS_LIB"pure_quanta";
"B"
$PN"2"28;
"A"
$PN"1"27;
%"Q_CAP"
"1","(-3600,4325)","0","pure_quanta","I155";
;
LOCATION"C2613"
$SEC"1"
CDS_SEC"1"
MATERIAL"X6S"
TOLERANCE"20%"
VALUE"22UF"
PART_NUMBER"CH622KMEB02"
VOLTAGE"4V"
PACK_TYPE"C0402"
CDS_LIB"pure_quanta";
"B"
$PN"2"32;
"A"
$PN"1"31;
%"Q_CAP"
"1","(-3625,5100)","0","pure_quanta","I156";
;
LOCATION"C2612"
$SEC"1"
CDS_SEC"1"
MATERIAL"X6S"
TOLERANCE"20%"
VALUE"22UF"
PART_NUMBER"CH622KMEB02"
VOLTAGE"4V"
PACK_TYPE"C0402"
CDS_LIB"pure_quanta";
"B"
$PN"2"28;
"A"
$PN"1"27;
%"Q_CAP"
"1","(-3175,5100)","0","pure_quanta","I157";
;
LOCATION"C2619"
$SEC"1"
CDS_SEC"1"
MATERIAL"X6S"
TOLERANCE"20%"
VALUE"22UF"
PART_NUMBER"CH622KMEB02"
VOLTAGE"4V"
PACK_TYPE"C0402"
CDS_LIB"pure_quanta";
"B"
$PN"2"28;
"A"
$PN"1"27;
%"Q_CAP"
"1","(-4075,5900)","0","pure_quanta","I158";
;
LOCATION"C2604"
$SEC"1"
CDS_SEC"1"
MATERIAL"X6S"
TOLERANCE"20%"
VALUE"22UF"
PART_NUMBER"CH622KMEB02"
VOLTAGE"4V"
PACK_TYPE"C0402"
CDS_LIB"pure_quanta";
"B"
$PN"2"30;
"A"
$PN"1"29;
%"Q_CAP"
"1","(-3625,5900)","0","pure_quanta","I159";
;
LOCATION"C2611"
$SEC"1"
CDS_SEC"1"
MATERIAL"X6S"
TOLERANCE"20%"
VALUE"22UF"
PART_NUMBER"CH622KMEB02"
VOLTAGE"4V"
PACK_TYPE"C0402"
CDS_LIB"pure_quanta";
"B"
$PN"2"30;
"A"
$PN"1"29;
%"Q_CAP"
"1","(-9100,4425)","0","pure_quanta","I16";
;
LOCATION"C2529"
$SEC"1"
CDS_SEC"1"
MATERIAL"X6S"
TOLERANCE"20%"
VALUE"22UF"
PART_NUMBER"CH622KMEB02"
VOLTAGE"4V"
PACK_TYPE"C0402"
CDS_LIB"pure_quanta";
"B"
$PN"2"13;
"A"
$PN"1"12;
%"Q_CAP"
"1","(-3175,5900)","0","pure_quanta","I160";
;
LOCATION"C2618"
$SEC"1"
CDS_SEC"1"
MATERIAL"X6S"
TOLERANCE"20%"
VALUE"22UF"
PART_NUMBER"CH622KMEB02"
VOLTAGE"4V"
PACK_TYPE"C0402"
CDS_LIB"pure_quanta";
"B"
$PN"2"30;
"A"
$PN"1"29;
%"Q_CAP"
"1","(-3150,4325)","0","pure_quanta","I161";
;
LOCATION"C2620"
$SEC"1"
CDS_SEC"1"
MATERIAL"X6S"
TOLERANCE"20%"
VALUE"22UF"
PART_NUMBER"CH622KMEB02"
VOLTAGE"4V"
PACK_TYPE"C0402"
CDS_LIB"pure_quanta";
"B"
$PN"2"32;
"A"
$PN"1"31;
%"Q_CAP"
"1","(-2725,5100)","0","pure_quanta","I162";
;
LOCATION"C2626"
$SEC"1"
CDS_SEC"1"
MATERIAL"X6S"
TOLERANCE"20%"
VALUE"22UF"
PART_NUMBER"CH622KMEB02"
VOLTAGE"4V"
PACK_TYPE"C0402"
CDS_LIB"pure_quanta";
"B"
$PN"2"28;
"A"
$PN"1"27;
%"Q_CAP"
"1","(-2275,5100)","0","pure_quanta","I163";
;
LOCATION"C2632"
$SEC"1"
CDS_SEC"1"
MATERIAL"X6S"
TOLERANCE"20%"
VALUE"22UF"
PART_NUMBER"CH622KMEB02"
VOLTAGE"4V"
PACK_TYPE"C0402"
CDS_LIB"pure_quanta";
"B"
$PN"2"28;
"A"
$PN"1"27;
%"Q_CAP"
"1","(-2725,5900)","0","pure_quanta","I164";
;
LOCATION"C2625"
$SEC"1"
CDS_SEC"1"
MATERIAL"X6S"
TOLERANCE"20%"
VALUE"22UF"
PART_NUMBER"CH622KMEB02"
VOLTAGE"4V"
PACK_TYPE"C0402"
CDS_LIB"pure_quanta";
"B"
$PN"2"30;
"A"
$PN"1"29;
%"Q_CAP"
"1","(-2275,5900)","0","pure_quanta","I165";
;
LOCATION"C2631"
$SEC"1"
CDS_SEC"1"
MATERIAL"X6S"
TOLERANCE"20%"
VALUE"22UF"
PART_NUMBER"CH622KMEB02"
VOLTAGE"4V"
PACK_TYPE"C0402"
CDS_LIB"pure_quanta";
"B"
$PN"2"30;
"A"
$PN"1"29;
%"Q_CAP"
"1","(-1825,5100)","0","pure_quanta","I166";
;
LOCATION"C2638"
$SEC"1"
CDS_SEC"1"
MATERIAL"X6S"
TOLERANCE"20%"
VALUE"22UF"
PART_NUMBER"CH622KMEB02"
VOLTAGE"4V"
PACK_TYPE"C0402"
CDS_LIB"pure_quanta";
"B"
$PN"2"28;
"A"
$PN"1"27;
%"Q_CAP"
"1","(-1375,5100)","0","pure_quanta","I167";
;
LOCATION"C2644"
$SEC"1"
CDS_SEC"1"
MATERIAL"X6S"
TOLERANCE"20%"
VALUE"22UF"
PART_NUMBER"CH622KMEB02"
VOLTAGE"4V"
PACK_TYPE"C0402"
CDS_LIB"pure_quanta";
"B"
$PN"2"28;
"A"
$PN"1"27;
%"Q_CAP"
"1","(-1825,5900)","0","pure_quanta","I168";
;
LOCATION"C2637"
$SEC"1"
CDS_SEC"1"
MATERIAL"X6S"
TOLERANCE"20%"
VALUE"22UF"
PART_NUMBER"CH622KMEB02"
VOLTAGE"4V"
PACK_TYPE"C0402"
CDS_LIB"pure_quanta";
"B"
$PN"2"30;
"A"
$PN"1"29;
%"Q_CAP"
"1","(-1375,5900)","0","pure_quanta","I169";
;
LOCATION"C2643"
$SEC"1"
CDS_SEC"1"
MATERIAL"X6S"
TOLERANCE"20%"
VALUE"22UF"
PART_NUMBER"CH622KMEB02"
VOLTAGE"4V"
PACK_TYPE"C0402"
CDS_LIB"pure_quanta";
"B"
$PN"2"30;
"A"
$PN"1"29;
%"UNIVERSAL_POWER"
"1","(-9100,4700)","0","pure_quanta_power","I17";
;
HDL_POWER"PVDDCR_SOC_P0"
CDS_LIB"pure_quanta_power";
"A"12;
%"Q_CAP"
"1","(-925,5100)","0","pure_quanta","I170";
;
LOCATION"C2650"
$SEC"1"
CDS_SEC"1"
MATERIAL"X6S"
TOLERANCE"20%"
VALUE"22UF"
PART_NUMBER"CH622KMEB02"
VOLTAGE"4V"
PACK_TYPE"C0402"
CDS_LIB"pure_quanta";
"B"
$PN"2"28;
"A"
$PN"1"27;
%"UNIVERSAL_GND"
"1","(-525,4725)","0","pure_quanta_power","I171";
;
CDS_LIB"pure_quanta_power"
HDL_POWER"GND";
"A"28;
%"Q_CAP"
"1","(-525,5100)","0","pure_quanta","I172";
;
LOCATION"C2655"
$SEC"1"
CDS_SEC"1"
MATERIAL"X6S"
TOLERANCE"20%"
VALUE"22UF"
PART_NUMBER"CH622KMEB02"
VOLTAGE"4V"
PACK_TYPE"C0402"
CDS_LIB"pure_quanta";
"B"
$PN"2"28;
"A"
$PN"1"27;
%"Q_CAP"
"1","(-925,5900)","0","pure_quanta","I173";
;
LOCATION"C2649"
$SEC"1"
CDS_SEC"1"
MATERIAL"X6S"
TOLERANCE"20%"
VALUE"22UF"
PART_NUMBER"CH622KMEB02"
VOLTAGE"4V"
PACK_TYPE"C0402"
CDS_LIB"pure_quanta";
"B"
$PN"2"30;
"A"
$PN"1"29;
%"UNIVERSAL_GND"
"1","(-525,5525)","0","pure_quanta_power","I174";
;
CDS_LIB"pure_quanta_power"
HDL_POWER"GND";
"A"30;
%"Q_CAP"
"1","(-525,5900)","0","pure_quanta","I175";
;
LOCATION"C2654"
$SEC"1"
CDS_SEC"1"
MATERIAL"X6S"
TOLERANCE"20%"
VALUE"22UF"
PART_NUMBER"CH622KMEB02"
VOLTAGE"4V"
PACK_TYPE"C0402"
CDS_LIB"pure_quanta";
"B"
$PN"2"30;
"A"
$PN"1"29;
%"Q_CAP"
"1","(-9100,5150)","0","pure_quanta","I18";
;
LOCATION"C2528"
$SEC"1"
CDS_SEC"1"
MATERIAL"X6S"
TOLERANCE"20%"
VALUE"22UF"
PART_NUMBER"CH622KMEB02"
VOLTAGE"4V"
PACK_TYPE"C0402"
CDS_LIB"pure_quanta";
"B"
$PN"2"11;
"A"
$PN"1"14;
%"Q_CAP"
"1","(-8650,4425)","0","pure_quanta","I19";
;
LOCATION"C2536"
$SEC"1"
CDS_SEC"1"
MATERIAL"X6S"
TOLERANCE"20%"
VALUE"22UF"
PART_NUMBER"CH622KMEB02"
VOLTAGE"4V"
PACK_TYPE"C0402"
CDS_LIB"pure_quanta";
"B"
$PN"2"13;
"A"
$PN"1"12;
%"UNIVERSAL_POWER"
"1","(-9075,1150)","0","pure_quanta_power","I2";
;
HDL_POWER"PVDDCR_SOC_P0"
CDS_LIB"pure_quanta_power";
"A"4;
%"Q_CAP"
"1","(-8650,5150)","0","pure_quanta","I20";
;
LOCATION"C2535"
$SEC"1"
CDS_SEC"1"
MATERIAL"X6S"
TOLERANCE"20%"
VALUE"22UF"
PART_NUMBER"CH622KMEB02"
VOLTAGE"4V"
PACK_TYPE"C0402"
CDS_LIB"pure_quanta";
"B"
$PN"2"11;
"A"
$PN"1"14;
%"UNIVERSAL_POWER"
"1","(-9100,5425)","0","pure_quanta_power","I21";
;
HDL_POWER"PVDDCR_SOC_P0"
CDS_LIB"pure_quanta_power";
"A"14;
%"Q_CAP"
"1","(-9100,5900)","0","pure_quanta","I22";
;
LOCATION"C2527"
$SEC"1"
CDS_SEC"1"
MATERIAL"X6S"
TOLERANCE"20%"
VALUE"22UF"
PART_NUMBER"CH622KMEB02"
VOLTAGE"4V"
PACK_TYPE"C0402"
CDS_LIB"pure_quanta";
"B"
$PN"2"16;
"A"
$PN"1"15;
%"UNIVERSAL_POWER"
"1","(-9100,6175)","0","pure_quanta_power","I23";
;
HDL_POWER"PVDDCR_SOC_P0"
CDS_LIB"pure_quanta_power";
"A"15;
%"Q_CAP"
"1","(-8650,5900)","0","pure_quanta","I24";
;
LOCATION"C2534"
$SEC"1"
CDS_SEC"1"
MATERIAL"X6S"
TOLERANCE"20%"
VALUE"22UF"
PART_NUMBER"CH622KMEB02"
VOLTAGE"4V"
PACK_TYPE"C0402"
CDS_LIB"pure_quanta";
"B"
$PN"2"16;
"A"
$PN"1"15;
%"Q_CAP"
"1","(-8175,875)","0","pure_quanta","I25";
;
LOCATION"C3927"
$SEC"1"
CDS_SEC"1"
MATERIAL"X6S"
TOLERANCE"20%"
VALUE"22UF"
PART_NUMBER"CH622KMEB02"
VOLTAGE"4V"
PACK_TYPE"C0402"
CDS_LIB"pure_quanta";
"B"
$PN"2"1;
"A"
$PN"1"4;
%"Q_CAP"
"1","(-7725,875)","0","pure_quanta","I26";
;
LOCATION"C3928"
$SEC"1"
CDS_SEC"1"
MATERIAL"X6S"
TOLERANCE"20%"
VALUE"22UF"
PART_NUMBER"CH622KMEB02"
VOLTAGE"4V"
PACK_TYPE"C0402"
CDS_LIB"pure_quanta";
"B"
$PN"2"1;
"A"
$PN"1"4;
%"Q_CAP"
"1","(-7275,875)","0","pure_quanta","I27";
;
LOCATION"C3929"
$SEC"1"
CDS_SEC"1"
MATERIAL"X6S"
TOLERANCE"20%"
VALUE"22UF"
PART_NUMBER"CH622KMEB02"
VOLTAGE"4V"
PACK_TYPE"C0402"
CDS_LIB"pure_quanta";
"B"
$PN"2"1;
"A"
$PN"1"4;
%"Q_CAP"
"1","(-8175,1575)","0","pure_quanta","I28";
;
LOCATION"C2547"
$SEC"1"
CDS_SEC"1"
MATERIAL"X6S"
TOLERANCE"20%"
VALUE"22UF"
PART_NUMBER"CH622KMEB02"
VOLTAGE"4V"
PACK_TYPE"C0402"
CDS_LIB"pure_quanta";
"B"
$PN"2"3;
"A"
$PN"1"2;
%"Q_CAP"
"1","(-7725,1575)","0","pure_quanta","I29";
;
LOCATION"C2554"
$SEC"1"
CDS_SEC"1"
MATERIAL"X6S"
TOLERANCE"20%"
VALUE"22UF"
PART_NUMBER"CH622KMEB02"
VOLTAGE"4V"
PACK_TYPE"C0402"
CDS_LIB"pure_quanta";
"B"
$PN"2"3;
"A"
$PN"1"2;
%"Q_CAP"
"1","(-8625,875)","0","pure_quanta","I3";
;
LOCATION"C3926"
$SEC"1"
CDS_SEC"1"
MATERIAL"X6S"
TOLERANCE"20%"
VALUE"22UF"
PART_NUMBER"CH622KMEB02"
VOLTAGE"4V"
PACK_TYPE"C0402"
CDS_LIB"pure_quanta";
"B"
$PN"2"1;
"A"
$PN"1"4;
%"Q_CAP"
"1","(-7275,1575)","0","pure_quanta","I30";
;
LOCATION"C2561"
$SEC"1"
CDS_SEC"1"
MATERIAL"X6S"
TOLERANCE"20%"
VALUE"22UF"
PART_NUMBER"CH622KMEB02"
VOLTAGE"4V"
PACK_TYPE"C0402"
CDS_LIB"pure_quanta";
"B"
$PN"2"3;
"A"
$PN"1"2;
%"Q_CAP"
"1","(-6825,875)","0","pure_quanta","I31";
;
LOCATION"C3930"
$SEC"1"
CDS_SEC"1"
MATERIAL"X6S"
TOLERANCE"20%"
VALUE"22UF"
PART_NUMBER"CH622KMEB02"
VOLTAGE"4V"
PACK_TYPE"C0402"
CDS_LIB"pure_quanta";
"B"
$PN"2"1;
"A"
$PN"1"4;
%"UNIVERSAL_GND"
"1","(-6375,500)","0","pure_quanta_power","I32";
;
CDS_LIB"pure_quanta_power"
HDL_POWER"GND";
"A"1;
%"Q_CAP"
"1","(-6375,875)","0","pure_quanta","I33";
;
LOCATION"C3931"
$SEC"1"
CDS_SEC"1"
MATERIAL"X6S"
TOLERANCE"20%"
VALUE"22UF"
PART_NUMBER"CH622KMEB02"
VOLTAGE"4V"
PACK_TYPE"C0402"
CDS_LIB"pure_quanta";
"B"
$PN"2"1;
"A"
$PN"1"4;
%"Q_CAP"
"1","(-6825,1575)","0","pure_quanta","I34";
;
LOCATION"C2568"
$SEC"1"
CDS_SEC"1"
MATERIAL"X6S"
TOLERANCE"20%"
VALUE"22UF"
PART_NUMBER"CH622KMEB02"
VOLTAGE"4V"
PACK_TYPE"C0402"
CDS_LIB"pure_quanta";
"B"
$PN"2"3;
"A"
$PN"1"2;
%"Q_CAP"
"1","(-6375,1575)","0","pure_quanta","I35";
;
LOCATION"C2575"
$SEC"1"
CDS_SEC"1"
MATERIAL"X6S"
TOLERANCE"20%"
VALUE"22UF"
PART_NUMBER"CH622KMEB02"
VOLTAGE"4V"
PACK_TYPE"C0402"
CDS_LIB"pure_quanta";
"B"
$PN"2"3;
"A"
$PN"1"2;
%"Q_CAP"
"1","(-8175,2300)","0","pure_quanta","I36";
;
LOCATION"C2546"
$SEC"1"
CDS_SEC"1"
MATERIAL"X6S"
TOLERANCE"20%"
VALUE"22UF"
PART_NUMBER"CH622KMEB02"
VOLTAGE"4V"
PACK_TYPE"C0402"
CDS_LIB"pure_quanta";
"B"
$PN"2"7;
"A"
$PN"1"6;
%"Q_CAP"
"1","(-8175,3000)","0","pure_quanta","I37";
;
LOCATION"C2545"
$SEC"1"
CDS_SEC"1"
MATERIAL"X6S"
TOLERANCE"20%"
VALUE"22UF"
PART_NUMBER"CH622KMEB02"
VOLTAGE"4V"
PACK_TYPE"C0402"
CDS_LIB"pure_quanta";
"B"
$PN"2"5;
"A"
$PN"1"10;
%"Q_CAP"
"1","(-7725,2300)","0","pure_quanta","I38";
;
LOCATION"C2553"
$SEC"1"
CDS_SEC"1"
MATERIAL"X6S"
TOLERANCE"20%"
VALUE"22UF"
PART_NUMBER"CH622KMEB02"
VOLTAGE"4V"
PACK_TYPE"C0402"
CDS_LIB"pure_quanta";
"B"
$PN"2"7;
"A"
$PN"1"6;
%"Q_CAP"
"1","(-7275,2300)","0","pure_quanta","I39";
;
LOCATION"C2560"
$SEC"1"
CDS_SEC"1"
MATERIAL"X6S"
TOLERANCE"20%"
VALUE"22UF"
PART_NUMBER"CH622KMEB02"
VOLTAGE"4V"
PACK_TYPE"C0402"
CDS_LIB"pure_quanta";
"B"
$PN"2"7;
"A"
$PN"1"6;
%"Q_CAP"
"1","(-9075,1575)","0","pure_quanta","I4";
;
LOCATION"C2533"
$SEC"1"
CDS_SEC"1"
MATERIAL"X6S"
TOLERANCE"20%"
VALUE"22UF"
PART_NUMBER"CH622KMEB02"
VOLTAGE"4V"
PACK_TYPE"C0402"
CDS_LIB"pure_quanta";
"B"
$PN"2"3;
"A"
$PN"1"2;
%"Q_CAP"
"1","(-7725,3000)","0","pure_quanta","I40";
;
LOCATION"C2552"
$SEC"1"
CDS_SEC"1"
MATERIAL"X6S"
TOLERANCE"20%"
VALUE"22UF"
PART_NUMBER"CH622KMEB02"
VOLTAGE"4V"
PACK_TYPE"C0402"
CDS_LIB"pure_quanta";
"B"
$PN"2"5;
"A"
$PN"1"10;
%"Q_CAP"
"1","(-7275,3000)","0","pure_quanta","I41";
;
LOCATION"C2559"
$SEC"1"
CDS_SEC"1"
MATERIAL"X6S"
TOLERANCE"20%"
VALUE"22UF"
PART_NUMBER"CH622KMEB02"
VOLTAGE"4V"
PACK_TYPE"C0402"
CDS_LIB"pure_quanta";
"B"
$PN"2"5;
"A"
$PN"1"10;
%"Q_CAP"
"1","(-8175,3725)","0","pure_quanta","I42";
;
LOCATION"C2544"
$SEC"1"
CDS_SEC"1"
MATERIAL"X6S"
TOLERANCE"20%"
VALUE"22UF"
PART_NUMBER"CH622KMEB02"
VOLTAGE"4V"
PACK_TYPE"C0402"
CDS_LIB"pure_quanta";
"B"
$PN"2"9;
"A"
$PN"1"8;
%"Q_CAP"
"1","(-7725,3725)","0","pure_quanta","I43";
;
LOCATION"C2551"
$SEC"1"
CDS_SEC"1"
MATERIAL"X6S"
TOLERANCE"20%"
VALUE"22UF"
PART_NUMBER"CH622KMEB02"
VOLTAGE"4V"
PACK_TYPE"C0402"
CDS_LIB"pure_quanta";
"B"
$PN"2"9;
"A"
$PN"1"8;
%"Q_CAP"
"1","(-7275,3725)","0","pure_quanta","I44";
;
LOCATION"C2558"
$SEC"1"
CDS_SEC"1"
MATERIAL"X6S"
TOLERANCE"20%"
VALUE"22UF"
PART_NUMBER"CH622KMEB02"
VOLTAGE"4V"
PACK_TYPE"C0402"
CDS_LIB"pure_quanta";
"B"
$PN"2"9;
"A"
$PN"1"8;
%"Q_CAP"
"1","(-6825,2300)","0","pure_quanta","I45";
;
LOCATION"C2567"
$SEC"1"
CDS_SEC"1"
MATERIAL"X6S"
TOLERANCE"20%"
VALUE"22UF"
PART_NUMBER"CH622KMEB02"
VOLTAGE"4V"
PACK_TYPE"C0402"
CDS_LIB"pure_quanta";
"B"
$PN"2"7;
"A"
$PN"1"6;
%"Q_CAP"
"1","(-6825,3000)","0","pure_quanta","I46";
;
LOCATION"C2566"
$SEC"1"
CDS_SEC"1"
MATERIAL"X6S"
TOLERANCE"20%"
VALUE"22UF"
PART_NUMBER"CH622KMEB02"
VOLTAGE"4V"
PACK_TYPE"C0402"
CDS_LIB"pure_quanta";
"B"
$PN"2"5;
"A"
$PN"1"10;
%"Q_CAP"
"1","(-6375,2300)","0","pure_quanta","I47";
;
LOCATION"C2574"
$SEC"1"
CDS_SEC"1"
MATERIAL"X6S"
TOLERANCE"20%"
VALUE"22UF"
PART_NUMBER"CH622KMEB02"
VOLTAGE"4V"
PACK_TYPE"C0402"
CDS_LIB"pure_quanta";
"B"
$PN"2"7;
"A"
$PN"1"6;
%"Q_CAP"
"1","(-6375,3000)","0","pure_quanta","I48";
;
LOCATION"C2573"
$SEC"1"
CDS_SEC"1"
MATERIAL"X6S"
TOLERANCE"20%"
VALUE"22UF"
PART_NUMBER"CH622KMEB02"
VOLTAGE"4V"
PACK_TYPE"C0402"
CDS_LIB"pure_quanta";
"B"
$PN"2"5;
"A"
$PN"1"10;
%"Q_CAP"
"1","(-6825,3725)","0","pure_quanta","I49";
;
LOCATION"C2565"
$SEC"1"
CDS_SEC"1"
MATERIAL"X6S"
TOLERANCE"20%"
VALUE"22UF"
PART_NUMBER"CH622KMEB02"
VOLTAGE"4V"
PACK_TYPE"C0402"
CDS_LIB"pure_quanta";
"B"
$PN"2"9;
"A"
$PN"1"8;
%"UNIVERSAL_POWER"
"1","(-9075,1850)","0","pure_quanta_power","I5";
;
HDL_POWER"PVDDCR_SOC_P0"
CDS_LIB"pure_quanta_power";
"A"2;
%"Q_CAP"
"1","(-6375,3725)","0","pure_quanta","I50";
;
LOCATION"C2572"
$SEC"1"
CDS_SEC"1"
MATERIAL"X6S"
TOLERANCE"20%"
VALUE"22UF"
PART_NUMBER"CH622KMEB02"
VOLTAGE"4V"
PACK_TYPE"C0402"
CDS_LIB"pure_quanta";
"B"
$PN"2"9;
"A"
$PN"1"8;
%"Q_CAP"
"1","(-5925,1575)","0","pure_quanta","I51";
;
LOCATION"C2582"
$SEC"1"
CDS_SEC"1"
MATERIAL"X6S"
TOLERANCE"20%"
VALUE"22UF"
PART_NUMBER"CH622KMEB02"
VOLTAGE"4V"
PACK_TYPE"C0402"
CDS_LIB"pure_quanta";
"B"
$PN"2"3;
"A"
$PN"1"2;
%"Q_CAP"
"1","(-5475,1575)","0","pure_quanta","I52";
;
LOCATION"C2589"
$SEC"1"
CDS_SEC"1"
MATERIAL"X6S"
TOLERANCE"20%"
VALUE"22UF"
PART_NUMBER"CH622KMEB02"
VOLTAGE"4V"
PACK_TYPE"C0402"
CDS_LIB"pure_quanta";
"B"
$PN"2"3;
"A"
$PN"1"2;
%"Q_CAP"
"1","(-4500,800)","0","pure_quanta","I53";
;
LOCATION"C3932"
$SEC"1"
CDS_SEC"1"
MATERIAL"X6S"
TOLERANCE"20%"
VALUE"22UF"
PART_NUMBER"CH622KMEB02"
VOLTAGE"4V"
PACK_TYPE"C0402"
CDS_LIB"pure_quanta";
"B"
$PN"2"26;
"A"
$PN"1"25;
%"UNIVERSAL_POWER"
"1","(-4500,1075)","0","pure_quanta_power","I54";
;
HDL_POWER"PVDD11_S3_P0"
CDS_LIB"pure_quanta_power";
"A"25;
%"UNIVERSAL_GND"
"1","(-5075,1200)","0","pure_quanta_power","I55";
;
CDS_LIB"pure_quanta_power"
HDL_POWER"GND";
"A"3;
%"Q_CAP"
"1","(-5075,1575)","0","pure_quanta","I56";
;
LOCATION"C2596"
$SEC"1"
CDS_SEC"1"
MATERIAL"X6S"
TOLERANCE"20%"
VALUE"22UF"
PART_NUMBER"CH622KMEB02"
VOLTAGE"4V"
PACK_TYPE"C0402"
CDS_LIB"pure_quanta";
"B"
$PN"2"3;
"A"
$PN"1"2;
%"UNIVERSAL_GND"
"1","(-5075,1925)","0","pure_quanta_power","I57";
;
CDS_LIB"pure_quanta_power"
HDL_POWER"GND";
"A"7;
%"Q_CAP"
"1","(-4500,1400)","0","pure_quanta","I58";
;
LOCATION"C2603"
$SEC"1"
CDS_SEC"1"
MATERIAL"X6S"
TOLERANCE"20%"
VALUE"22UF"
PART_NUMBER"CH622KMEB02"
VOLTAGE"4V"
PACK_TYPE"C0402"
CDS_LIB"pure_quanta";
"B"
$PN"2"24;
"A"
$PN"1"23;
%"UNIVERSAL_POWER"
"1","(-4500,1675)","0","pure_quanta_power","I59";
;
HDL_POWER"PVDD11_S3_P0"
CDS_LIB"pure_quanta_power";
"A"23;
%"Q_CAP"
"1","(-8625,1575)","0","pure_quanta","I6";
;
LOCATION"C2540"
$SEC"1"
CDS_SEC"1"
MATERIAL"X6S"
TOLERANCE"20%"
VALUE"22UF"
PART_NUMBER"CH622KMEB02"
VOLTAGE"4V"
PACK_TYPE"C0402"
CDS_LIB"pure_quanta";
"B"
$PN"2"3;
"A"
$PN"1"2;
%"Q_CAP"
"1","(-4500,2000)","0","pure_quanta","I60";
;
LOCATION"C2602"
$SEC"1"
CDS_SEC"1"
MATERIAL"X6S"
TOLERANCE"20%"
VALUE"22UF"
PART_NUMBER"CH622KMEB02"
VOLTAGE"4V"
PACK_TYPE"C0402"
CDS_LIB"pure_quanta";
"B"
$PN"2"22;
"A"
$PN"1"21;
%"Q_CAP"
"1","(-5925,2300)","0","pure_quanta","I61";
;
LOCATION"C2581"
$SEC"1"
CDS_SEC"1"
MATERIAL"X6S"
TOLERANCE"20%"
VALUE"22UF"
PART_NUMBER"CH622KMEB02"
VOLTAGE"4V"
PACK_TYPE"C0402"
CDS_LIB"pure_quanta";
"B"
$PN"2"7;
"A"
$PN"1"6;
%"Q_CAP"
"1","(-5925,3000)","0","pure_quanta","I62";
;
LOCATION"C2580"
$SEC"1"
CDS_SEC"1"
MATERIAL"X6S"
TOLERANCE"20%"
VALUE"22UF"
PART_NUMBER"CH622KMEB02"
VOLTAGE"4V"
PACK_TYPE"C0402"
CDS_LIB"pure_quanta";
"B"
$PN"2"5;
"A"
$PN"1"10;
%"Q_CAP"
"1","(-5475,2300)","0","pure_quanta","I63";
;
LOCATION"C2588"
$SEC"1"
CDS_SEC"1"
MATERIAL"X6S"
TOLERANCE"20%"
VALUE"22UF"
PART_NUMBER"CH622KMEB02"
VOLTAGE"4V"
PACK_TYPE"C0402"
CDS_LIB"pure_quanta";
"B"
$PN"2"7;
"A"
$PN"1"6;
%"Q_CAP"
"1","(-5475,3000)","0","pure_quanta","I64";
;
LOCATION"C2587"
$SEC"1"
CDS_SEC"1"
MATERIAL"X6S"
TOLERANCE"20%"
VALUE"22UF"
PART_NUMBER"CH622KMEB02"
VOLTAGE"4V"
PACK_TYPE"C0402"
CDS_LIB"pure_quanta";
"B"
$PN"2"5;
"A"
$PN"1"10;
%"Q_CAP"
"1","(-5925,3725)","0","pure_quanta","I65";
;
LOCATION"C2579"
$SEC"1"
CDS_SEC"1"
MATERIAL"X6S"
TOLERANCE"20%"
VALUE"22UF"
PART_NUMBER"CH622KMEB02"
VOLTAGE"4V"
PACK_TYPE"C0402"
CDS_LIB"pure_quanta";
"B"
$PN"2"9;
"A"
$PN"1"8;
%"Q_CAP"
"1","(-5475,3725)","0","pure_quanta","I66";
;
LOCATION"C2586"
$SEC"1"
CDS_SEC"1"
MATERIAL"X6S"
TOLERANCE"20%"
VALUE"22UF"
PART_NUMBER"CH622KMEB02"
VOLTAGE"4V"
PACK_TYPE"C0402"
CDS_LIB"pure_quanta";
"B"
$PN"2"9;
"A"
$PN"1"8;
%"Q_CAP"
"1","(-5075,2300)","0","pure_quanta","I67";
;
LOCATION"C2595"
$SEC"1"
CDS_SEC"1"
MATERIAL"X6S"
TOLERANCE"20%"
VALUE"22UF"
PART_NUMBER"CH622KMEB02"
VOLTAGE"4V"
PACK_TYPE"C0402"
CDS_LIB"pure_quanta";
"B"
$PN"2"7;
"A"
$PN"1"6;
%"UNIVERSAL_GND"
"1","(-5075,2625)","0","pure_quanta_power","I68";
;
CDS_LIB"pure_quanta_power"
HDL_POWER"GND";
"A"5;
%"Q_CAP"
"1","(-5075,3000)","0","pure_quanta","I69";
;
LOCATION"C2594"
$SEC"1"
CDS_SEC"1"
MATERIAL"X6S"
TOLERANCE"20%"
VALUE"22UF"
PART_NUMBER"CH622KMEB02"
VOLTAGE"4V"
PACK_TYPE"C0402"
CDS_LIB"pure_quanta";
"B"
$PN"2"5;
"A"
$PN"1"10;
%"Q_CAP"
"1","(-9075,2300)","0","pure_quanta","I7";
;
LOCATION"C2532"
$SEC"1"
CDS_SEC"1"
MATERIAL"X6S"
TOLERANCE"20%"
VALUE"22UF"
PART_NUMBER"CH622KMEB02"
VOLTAGE"4V"
PACK_TYPE"C0402"
CDS_LIB"pure_quanta";
"B"
$PN"2"7;
"A"
$PN"1"6;
%"UNIVERSAL_POWER"
"1","(-4500,2275)","0","pure_quanta_power","I70";
;
HDL_POWER"PVDD11_S3_P0"
CDS_LIB"pure_quanta_power";
"A"21;
%"Q_CAP"
"1","(-4500,2625)","0","pure_quanta","I71";
;
LOCATION"C2601"
$SEC"1"
CDS_SEC"1"
MATERIAL"X6S"
TOLERANCE"20%"
VALUE"22UF"
PART_NUMBER"CH622KMEB02"
VOLTAGE"4V"
PACK_TYPE"C0402"
CDS_LIB"pure_quanta";
"B"
$PN"2"20;
"A"
$PN"1"19;
%"UNIVERSAL_POWER"
"1","(-4500,2900)","0","pure_quanta_power","I72";
;
HDL_POWER"PVDD11_S3_P0"
CDS_LIB"pure_quanta_power";
"A"19;
%"UNIVERSAL_GND"
"1","(-5075,3350)","0","pure_quanta_power","I73";
;
CDS_LIB"pure_quanta_power"
HDL_POWER"GND";
"A"9;
%"Q_CAP"
"1","(-5075,3725)","0","pure_quanta","I74";
;
LOCATION"C2593"
$SEC"1"
CDS_SEC"1"
MATERIAL"X6S"
TOLERANCE"20%"
VALUE"22UF"
PART_NUMBER"CH622KMEB02"
VOLTAGE"4V"
PACK_TYPE"C0402"
CDS_LIB"pure_quanta";
"B"
$PN"2"9;
"A"
$PN"1"8;
%"UNIVERSAL_GND"
"1","(-5100,4050)","0","pure_quanta_power","I75";
;
CDS_LIB"pure_quanta_power"
HDL_POWER"GND";
"A"13;
%"Q_CAP"
"1","(-4500,3275)","0","pure_quanta","I76";
;
LOCATION"C2600"
$SEC"1"
CDS_SEC"1"
MATERIAL"X6S"
TOLERANCE"20%"
VALUE"22UF"
PART_NUMBER"CH622KMEB02"
VOLTAGE"4V"
PACK_TYPE"C0402"
CDS_LIB"pure_quanta";
"B"
$PN"2"18;
"A"
$PN"1"17;
%"UNIVERSAL_POWER"
"1","(-4500,3550)","0","pure_quanta_power","I77";
;
HDL_POWER"PVDD11_S3_P0"
CDS_LIB"pure_quanta_power";
"A"17;
%"Q_CAP"
"1","(-8200,4425)","0","pure_quanta","I78";
;
LOCATION"C2543"
$SEC"1"
CDS_SEC"1"
MATERIAL"X6S"
TOLERANCE"20%"
VALUE"22UF"
PART_NUMBER"CH622KMEB02"
VOLTAGE"4V"
PACK_TYPE"C0402"
CDS_LIB"pure_quanta";
"B"
$PN"2"13;
"A"
$PN"1"12;
%"Q_CAP"
"1","(-8200,5150)","0","pure_quanta","I79";
;
LOCATION"C2542"
$SEC"1"
CDS_SEC"1"
MATERIAL"X6S"
TOLERANCE"20%"
VALUE"22UF"
PART_NUMBER"CH622KMEB02"
VOLTAGE"4V"
PACK_TYPE"C0402"
CDS_LIB"pure_quanta";
"B"
$PN"2"11;
"A"
$PN"1"14;
%"UNIVERSAL_POWER"
"1","(-9075,2575)","0","pure_quanta_power","I8";
;
HDL_POWER"PVDDCR_SOC_P0"
CDS_LIB"pure_quanta_power";
"A"6;
%"Q_CAP"
"1","(-7750,4425)","0","pure_quanta","I80";
;
LOCATION"C2550"
$SEC"1"
CDS_SEC"1"
MATERIAL"X6S"
TOLERANCE"20%"
VALUE"22UF"
PART_NUMBER"CH622KMEB02"
VOLTAGE"4V"
PACK_TYPE"C0402"
CDS_LIB"pure_quanta";
"B"
$PN"2"13;
"A"
$PN"1"12;
%"Q_CAP"
"1","(-7750,5150)","0","pure_quanta","I81";
;
LOCATION"C2549"
$SEC"1"
CDS_SEC"1"
MATERIAL"X6S"
TOLERANCE"20%"
VALUE"22UF"
PART_NUMBER"CH622KMEB02"
VOLTAGE"4V"
PACK_TYPE"C0402"
CDS_LIB"pure_quanta";
"B"
$PN"2"11;
"A"
$PN"1"14;
%"Q_CAP"
"1","(-7300,4425)","0","pure_quanta","I82";
;
LOCATION"C2557"
$SEC"1"
CDS_SEC"1"
MATERIAL"X6S"
TOLERANCE"20%"
VALUE"22UF"
PART_NUMBER"CH622KMEB02"
VOLTAGE"4V"
PACK_TYPE"C0402"
CDS_LIB"pure_quanta";
"B"
$PN"2"13;
"A"
$PN"1"12;
%"Q_CAP"
"1","(-7300,5150)","0","pure_quanta","I83";
;
LOCATION"C2556"
$SEC"1"
CDS_SEC"1"
MATERIAL"X6S"
TOLERANCE"20%"
VALUE"22UF"
PART_NUMBER"CH622KMEB02"
VOLTAGE"4V"
PACK_TYPE"C0402"
CDS_LIB"pure_quanta";
"B"
$PN"2"11;
"A"
$PN"1"14;
%"Q_CAP"
"1","(-8200,5900)","0","pure_quanta","I84";
;
LOCATION"C2541"
$SEC"1"
CDS_SEC"1"
MATERIAL"X6S"
TOLERANCE"20%"
VALUE"22UF"
PART_NUMBER"CH622KMEB02"
VOLTAGE"4V"
PACK_TYPE"C0402"
CDS_LIB"pure_quanta";
"B"
$PN"2"16;
"A"
$PN"1"15;
%"Q_CAP"
"1","(-7750,5900)","0","pure_quanta","I85";
;
LOCATION"C2548"
$SEC"1"
CDS_SEC"1"
MATERIAL"X6S"
TOLERANCE"20%"
VALUE"22UF"
PART_NUMBER"CH622KMEB02"
VOLTAGE"4V"
PACK_TYPE"C0402"
CDS_LIB"pure_quanta";
"B"
$PN"2"16;
"A"
$PN"1"15;
%"Q_CAP"
"1","(-7300,5900)","0","pure_quanta","I86";
;
LOCATION"C2555"
$SEC"1"
CDS_SEC"1"
MATERIAL"X6S"
TOLERANCE"20%"
VALUE"22UF"
PART_NUMBER"CH622KMEB02"
VOLTAGE"4V"
PACK_TYPE"C0402"
CDS_LIB"pure_quanta";
"B"
$PN"2"16;
"A"
$PN"1"15;
%"Q_CAP"
"1","(-6850,4425)","0","pure_quanta","I87";
;
LOCATION"C2564"
$SEC"1"
CDS_SEC"1"
MATERIAL"X6S"
TOLERANCE"20%"
VALUE"22UF"
PART_NUMBER"CH622KMEB02"
VOLTAGE"4V"
PACK_TYPE"C0402"
CDS_LIB"pure_quanta";
"B"
$PN"2"13;
"A"
$PN"1"12;
%"Q_CAP"
"1","(-6850,5150)","0","pure_quanta","I88";
;
LOCATION"C2563"
$SEC"1"
CDS_SEC"1"
MATERIAL"X6S"
TOLERANCE"20%"
VALUE"22UF"
PART_NUMBER"CH622KMEB02"
VOLTAGE"4V"
PACK_TYPE"C0402"
CDS_LIB"pure_quanta";
"B"
$PN"2"11;
"A"
$PN"1"14;
%"Q_CAP"
"1","(-6400,4425)","0","pure_quanta","I89";
;
LOCATION"C2571"
$SEC"1"
CDS_SEC"1"
MATERIAL"X6S"
TOLERANCE"20%"
VALUE"22UF"
PART_NUMBER"CH622KMEB02"
VOLTAGE"4V"
PACK_TYPE"C0402"
CDS_LIB"pure_quanta";
"B"
$PN"2"13;
"A"
$PN"1"12;
%"Q_CAP"
"1","(-9075,3000)","0","pure_quanta","I9";
;
LOCATION"C2531"
$SEC"1"
CDS_SEC"1"
MATERIAL"X6S"
TOLERANCE"20%"
VALUE"22UF"
PART_NUMBER"CH622KMEB02"
VOLTAGE"4V"
PACK_TYPE"C0402"
CDS_LIB"pure_quanta";
"B"
$PN"2"5;
"A"
$PN"1"10;
%"Q_CAP"
"1","(-6400,5150)","0","pure_quanta","I90";
;
LOCATION"C2570"
$SEC"1"
CDS_SEC"1"
MATERIAL"X6S"
TOLERANCE"20%"
VALUE"22UF"
PART_NUMBER"CH622KMEB02"
VOLTAGE"4V"
PACK_TYPE"C0402"
CDS_LIB"pure_quanta";
"B"
$PN"2"11;
"A"
$PN"1"14;
%"Q_CAP"
"1","(-6850,5900)","0","pure_quanta","I91";
;
LOCATION"C2562"
$SEC"1"
CDS_SEC"1"
MATERIAL"X6S"
TOLERANCE"20%"
VALUE"22UF"
PART_NUMBER"CH622KMEB02"
VOLTAGE"4V"
PACK_TYPE"C0402"
CDS_LIB"pure_quanta";
"B"
$PN"2"16;
"A"
$PN"1"15;
%"Q_CAP"
"1","(-6400,5900)","0","pure_quanta","I92";
;
LOCATION"C2569"
$SEC"1"
CDS_SEC"1"
MATERIAL"X6S"
TOLERANCE"20%"
VALUE"22UF"
PART_NUMBER"CH622KMEB02"
VOLTAGE"4V"
PACK_TYPE"C0402"
CDS_LIB"pure_quanta";
"B"
$PN"2"16;
"A"
$PN"1"15;
%"Q_CAP"
"1","(-5950,4425)","0","pure_quanta","I93";
;
LOCATION"C2578"
$SEC"1"
CDS_SEC"1"
MATERIAL"X6S"
TOLERANCE"20%"
VALUE"22UF"
PART_NUMBER"CH622KMEB02"
VOLTAGE"4V"
PACK_TYPE"C0402"
CDS_LIB"pure_quanta";
"B"
$PN"2"13;
"A"
$PN"1"12;
%"Q_CAP"
"1","(-5950,5150)","0","pure_quanta","I94";
;
LOCATION"C2577"
$SEC"1"
CDS_SEC"1"
MATERIAL"X6S"
TOLERANCE"20%"
VALUE"22UF"
PART_NUMBER"CH622KMEB02"
VOLTAGE"4V"
PACK_TYPE"C0402"
CDS_LIB"pure_quanta";
"B"
$PN"2"11;
"A"
$PN"1"14;
%"Q_CAP"
"1","(-5500,4425)","0","pure_quanta","I95";
;
LOCATION"C2585"
$SEC"1"
CDS_SEC"1"
MATERIAL"X6S"
TOLERANCE"20%"
VALUE"22UF"
PART_NUMBER"CH622KMEB02"
VOLTAGE"4V"
PACK_TYPE"C0402"
CDS_LIB"pure_quanta";
"B"
$PN"2"13;
"A"
$PN"1"12;
%"Q_CAP"
"1","(-5500,5150)","0","pure_quanta","I96";
;
LOCATION"C2584"
$SEC"1"
CDS_SEC"1"
MATERIAL"X6S"
TOLERANCE"20%"
VALUE"22UF"
PART_NUMBER"CH622KMEB02"
VOLTAGE"4V"
PACK_TYPE"C0402"
CDS_LIB"pure_quanta";
"B"
$PN"2"11;
"A"
$PN"1"14;
%"Q_CAP"
"1","(-5950,5900)","0","pure_quanta","I97";
;
LOCATION"C2576"
$SEC"1"
CDS_SEC"1"
MATERIAL"X6S"
TOLERANCE"20%"
VALUE"22UF"
PART_NUMBER"CH622KMEB02"
VOLTAGE"4V"
PACK_TYPE"C0402"
CDS_LIB"pure_quanta";
"B"
$PN"2"16;
"A"
$PN"1"15;
%"Q_CAP"
"1","(-5500,5900)","0","pure_quanta","I98";
;
LOCATION"C2583"
$SEC"1"
CDS_SEC"1"
MATERIAL"X6S"
TOLERANCE"20%"
VALUE"22UF"
PART_NUMBER"CH622KMEB02"
VOLTAGE"4V"
PACK_TYPE"C0402"
CDS_LIB"pure_quanta";
"B"
$PN"2"16;
"A"
$PN"1"15;
%"Q_CAP"
"1","(-5100,4425)","0","pure_quanta","I99";
;
LOCATION"C2592"
$SEC"1"
CDS_SEC"1"
MATERIAL"X6S"
TOLERANCE"20%"
VALUE"22UF"
PART_NUMBER"CH622KMEB02"
VOLTAGE"4V"
PACK_TYPE"C0402"
CDS_LIB"pure_quanta";
"B"
$PN"2"13;
"A"
$PN"1"12;
END.
